(kicad_pcb
	(version 20260206)
	(generator "pcbnew")
	(generator_version "10.0")
	(general
		(thickness 1.6)
		(legacy_teardrops no)
	)
	(paper "A4")
	(title_block
		(title "Bryce Canyon_IOM_M2_16342-2_OCP.brd")
		(comment 1 "Bryce Canyon / footprints 1146-1146 of 1146")
	)
	(layers
		(0 "F.Cu" signal "TOP")
		(4 "In1.Cu" signal "L2GND")
		(6 "In2.Cu" signal "L3")
		(8 "In3.Cu" signal "L4VCC")
		(10 "In4.Cu" signal "L5VCC")
		(12 "In5.Cu" signal "L6")
		(14 "In6.Cu" signal "L7GND")
		(2 "B.Cu" signal "BOTTOM")
		(9 "F.Adhes" user "F.Adhesive")
		(11 "B.Adhes" user "B.Adhesive")
		(13 "F.Paste" user "Package Geometry/Pastemask Top")
		(15 "B.Paste" user "Package Geometry/Pastemask Bottom")
		(5 "F.SilkS" user "Ref Des/Silkscreen Top")
		(7 "B.SilkS" user "Ref Des/Silkscreen Bottom")
		(1 "F.Mask" user "Board Geometry/Soldermask Top")
		(3 "B.Mask" user "Board Geometry/Soldermask Bottom")
		(17 "Dwgs.User" user "User.Drawings")
		(19 "Cmts.User" user "User.Comments")
		(21 "Eco1.User" user "User.Eco1")
		(23 "Eco2.User" user "User.Eco2")
		(25 "Edge.Cuts" user "Board Geometry/Outline")
		(27 "Margin" user)
		(31 "F.CrtYd" user "Package Geometry/Place Bound Top")
		(29 "B.CrtYd" user "Package Geometry/Place Bound Bottom")
		(35 "F.Fab" user "Ref Des/Assembly Top")
		(33 "B.Fab" user "Ref Des/Assembly Bottom")
	)
	(footprint ""
		(layer "B.Cu")
		(at 55.499 -124.206 180)
		(property "Reference" "R702"
			(at 0 0 0)
			(layer "B.SilkS")
			(hide yes)
			(effects
				(font
					(size 1.27 1.27)
				)
				(justify mirror)
			)
		)
		(property "Value" "4K7R2F-GP"
			(at -0.064008 -3.993896 180)
			(unlocked yes)
			(layer "B.Fab")
			(hide yes)
			(effects
				(font
					(size 1.016 1.016)
					(thickness 0.1524)
				)
				(justify mirror)
			)
		)
		(property "Device Type" "R402H16"
			(at -0.064008 -5.517896 180)
			(unlocked yes)
			(layer "B.Fab")
			(hide yes)
			(effects
				(font
					(size 1.016 1.016)
					(thickness 0.1524)
				)
				(justify mirror)
			)
		)
		(duplicate_pad_numbers_are_jumpers no)
		(fp_line
			(start 0.508 -0.9398)
			(end 0.508 0.9398)
			(stroke
				(width 0.1524)
				(type default)
			)
			(layer "B.SilkS")
		)
		(fp_line
			(start -0.508 -0.9398)
			(end 0.508 -0.9398)
			(stroke
				(width 0.1524)
				(type default)
			)
			(layer "B.SilkS")
		)
		(fp_rect
			(start 0.508 0.9398)
			(end -0.508 -0.9398)
			(stroke
				(width 0)
				(type default)
			)
			(fill no)
			(layer "B.CrtYd")
		)
		(fp_rect
			(start 0.508 0.9398)
			(end -0.508 -0.9398)
			(stroke
				(width 0)
				(type default)
			)
			(fill no)
			(layer "B.Fab")
		)
		(pad "1" smd custom
			(at 0 -0.4445)
			(size 0.1397 0.1397)
			(layers "B.Cu" "B.Mask" "B.Paste")
			(net "P3V3_STBY")
			(options
				(clearance outline)
				(anchor circle)
			)
			(primitives
				(gr_poly
					(pts
						(arc
							(start -0.1778 0.2794)
							(mid -0.249642 0.249642)
							(end -0.2794 0.1778)
						)
						(arc
							(start -0.2794 -0.1778)
							(mid -0.249642 -0.249642)
							(end -0.1778 -0.2794)
						)
						(arc
							(start 0.1778 -0.2794)
							(mid 0.249642 -0.249642)
							(end 0.2794 -0.1778)
						)
						(arc
							(start 0.2794 0.1778)
							(mid 0.249642 0.249642)
							(end 0.1778 0.2794)
						)
					)
					(width 0)
					(fill yes)
				)
			)
		)
		(pad "2" smd custom
			(at 0 0.4445)
			(size 0.1397 0.1397)
			(layers "B.Cu" "B.Mask" "B.Paste")
			(net "DEBUG_RST_BTN_N_R")
			(options
				(clearance outline)
				(anchor circle)
			)
			(primitives
				(gr_poly
					(pts
						(arc
							(start -0.1778 0.2794)
							(mid -0.249642 0.249642)
							(end -0.2794 0.1778)
						)
						(arc
							(start -0.2794 -0.1778)
							(mid -0.249642 -0.249642)
							(end -0.1778 -0.2794)
						)
						(arc
							(start 0.1778 -0.2794)
							(mid 0.249642 -0.249642)
							(end 0.2794 -0.1778)
						)
						(arc
							(start 0.2794 0.1778)
							(mid 0.249642 0.249642)
							(end 0.1778 0.2794)
						)
					)
					(width 0)
					(fill yes)
				)
			)
		)
	)
)
